(kicad_pcb
	(version 20260206)
	(generator "pcbnew")
	(generator_version "10.0")
	(general
		(thickness 1.6)
		(legacy_teardrops no)
	)
	(paper "A4")
	(title_block
		(title "panther-plus-userver — 13130-1b_20150205.brd")
		(comment 1 "Honey Badger (Wiwynn) / footprints 1433-1440 of 1509")
	)
	(layers
		(0 "F.Cu" signal "TOP")
		(4 "In1.Cu" signal "L2")
		(6 "In2.Cu" signal "L3")
		(8 "In3.Cu" signal "L4")
		(10 "In4.Cu" signal "L5")
		(12 "In5.Cu" signal "L6")
		(14 "In6.Cu" signal "L7")
		(16 "In7.Cu" signal "L8")
		(18 "In8.Cu" signal "L9")
		(20 "In9.Cu" signal "L10")
		(22 "In10.Cu" signal "L11")
		(2 "B.Cu" signal "BOTTOM")
		(9 "F.Adhes" user "F.Adhesive")
		(11 "B.Adhes" user "B.Adhesive")
		(13 "F.Paste" user "Package Geometry/Pastemask Top")
		(15 "B.Paste" user "Package Geometry/Pastemask Bottom")
		(5 "F.SilkS" user "Ref Des/Silkscreen Top")
		(7 "B.SilkS" user "Ref Des/Silkscreen Bottom")
		(1 "F.Mask" user "Board Geometry/Soldermask Top")
		(3 "B.Mask" user "Board Geometry/Soldermask Bottom")
		(17 "Dwgs.User" user "User.Drawings")
		(19 "Cmts.User" user "User.Comments")
		(21 "Eco1.User" user "User.Eco1")
		(23 "Eco2.User" user "User.Eco2")
		(25 "Edge.Cuts" user "Board Geometry/Outline")
		(27 "Margin" user)
		(31 "F.CrtYd" user "Package Geometry/Place Bound Top")
		(29 "B.CrtYd" user "Package Geometry/Place Bound Bottom")
		(35 "F.Fab" user "Ref Des/Assembly Top")
		(33 "B.Fab" user "Ref Des/Assembly Bottom")
	)
	(footprint ""
		(layer "B.Cu")
		(at 15.367 -31.369)
		(property "Reference" "PC159"
			(at 0 0 0)
			(layer "B.SilkS")
			(hide yes)
			(effects
				(font
					(size 1.27 1.27)
				)
				(justify mirror)
			)
		)
		(property "Value" "SC4D7U25V5KX-1-GP"
			(at 0 -4.9022 0)
			(unlocked yes)
			(layer "B.Fab")
			(hide yes)
			(effects
				(font
					(size 1.016 1.016)
					(thickness 0.1524)
				)
				(justify mirror)
			)
		)
		(property "Device Type" "C805H58"
			(at 0 -6.8072 0)
			(unlocked yes)
			(layer "B.Fab")
			(hide yes)
			(effects
				(font
					(size 1.016 1.016)
					(thickness 0.1524)
				)
				(justify mirror)
			)
		)
		(duplicate_pad_numbers_are_jumpers no)
		(fp_line
			(start -0.6096 0)
			(end 0.6096 0)
			(stroke
				(width 0.3048)
				(type default)
			)
			(layer "B.SilkS")
		)
		(fp_poly
			(pts
				(xy 0.9017 1.4351) (xy -0.9017 1.4351) (xy -0.9017 -1.4351) (xy 0.9017 -1.4351)
			)
			(stroke
				(width 0)
				(type default)
			)
			(fill no)
			(layer "B.CrtYd")
		)
		(fp_poly
			(pts
				(xy -0.9017 1.4351) (xy -0.9017 -1.4351) (xy 0.9017 -1.4351) (xy 0.9017 1.4351)
			)
			(stroke
				(width 0)
				(type default)
			)
			(fill no)
			(layer "B.Fab")
		)
		(pad "1" smd rect
			(at 0 -0.8382 180)
			(size 1.5494 0.9398)
			(layers "B.Cu" "B.Mask" "B.Paste")
			(net "P3V3_STBY_EN")
		)
		(pad "2" smd rect
			(at 0 0.8382 180)
			(size 1.5494 0.9398)
			(layers "B.Cu" "B.Mask" "B.Paste")
			(net "AGND_P3V3_STBY")
		)
	)
	(footprint ""
		(layer "B.Cu")
		(at 75.565 -58.674 -90)
		(property "Reference" "R135"
			(at 0 0 90)
			(layer "B.SilkS")
			(hide yes)
			(effects
				(font
					(size 1.27 1.27)
				)
				(justify mirror)
			)
		)
		(property "Value" "0R2J-2-GP"
			(at -0.064008 -3.993896 270)
			(unlocked yes)
			(layer "B.Fab")
			(hide yes)
			(effects
				(font
					(size 1.016 1.016)
					(thickness 0.1524)
				)
				(justify mirror)
			)
		)
		(property "Device Type" "R402H16"
			(at -0.064008 -5.517896 270)
			(unlocked yes)
			(layer "B.Fab")
			(hide yes)
			(effects
				(font
					(size 1.016 1.016)
					(thickness 0.1524)
				)
				(justify mirror)
			)
		)
		(duplicate_pad_numbers_are_jumpers no)
		(fp_rect
			(start 0.381 0.8382)
			(end -0.381 -0.8382)
			(stroke
				(width 0)
				(type default)
			)
			(fill no)
			(layer "B.CrtYd")
		)
		(fp_rect
			(start 0.381 0.8382)
			(end -0.381 -0.8382)
			(stroke
				(width 0)
				(type default)
			)
			(fill no)
			(layer "B.Fab")
		)
		(pad "1" smd custom
			(at 0 -0.4318 90)
			(size 0.127 0.127)
			(layers "B.Cu" "B.Mask" "B.Paste")
			(net "VOL1_SEN_DATA")
			(options
				(clearance outline)
				(anchor circle)
			)
			(primitives
				(gr_poly
					(pts
						(arc
							(start -0.2032 0.2794)
							(mid -0.239121 0.264521)
							(end -0.254 0.2286)
						)
						(arc
							(start -0.254 -0.2286)
							(mid -0.239121 -0.264521)
							(end -0.2032 -0.2794)
						)
						(arc
							(start 0.2032 -0.2794)
							(mid 0.239121 -0.264521)
							(end 0.254 -0.2286)
						)
						(arc
							(start 0.254 0.2286)
							(mid 0.239121 0.264521)
							(end 0.2032 0.2794)
						)
					)
					(width 0)
					(fill yes)
				)
			)
		)
		(pad "2" smd custom
			(at 0 0.4318 90)
			(size 0.127 0.127)
			(layers "B.Cu" "B.Mask" "B.Paste")
			(net "SMB_HOST_LV_DATA")
			(options
				(clearance outline)
				(anchor circle)
			)
			(primitives
				(gr_poly
					(pts
						(arc
							(start -0.2032 0.2794)
							(mid -0.239121 0.264521)
							(end -0.254 0.2286)
						)
						(arc
							(start -0.254 -0.2286)
							(mid -0.239121 -0.264521)
							(end -0.2032 -0.2794)
						)
						(arc
							(start 0.2032 -0.2794)
							(mid 0.239121 -0.264521)
							(end 0.254 -0.2286)
						)
						(arc
							(start 0.254 0.2286)
							(mid 0.239121 0.264521)
							(end 0.2032 0.2794)
						)
					)
					(width 0)
					(fill yes)
				)
			)
		)
	)
	(footprint ""
		(layer "B.Cu")
		(at 39.37 -14.605 -90)
		(property "Reference" "R430"
			(at 0 0 90)
			(layer "B.SilkS")
			(hide yes)
			(effects
				(font
					(size 1.27 1.27)
				)
				(justify mirror)
			)
		)
		(property "Value" "43D2R2F-GP"
			(at -1.7907 -1.1176 270)
			(unlocked yes)
			(layer "B.Fab")
			(hide yes)
			(effects
				(font
					(size 1.016 1.016)
					(thickness 0.1524)
				)
				(justify mirror)
			)
		)
		(property "Device Type" "R402H16"
			(at -1.7907 -2.6416 270)
			(unlocked yes)
			(layer "B.Fab")
			(hide yes)
			(effects
				(font
					(size 1.016 1.016)
					(thickness 0.1524)
				)
				(justify mirror)
			)
		)
		(duplicate_pad_numbers_are_jumpers no)
		(fp_rect
			(start 0.381 0.8382)
			(end -0.381 -0.8382)
			(stroke
				(width 0)
				(type default)
			)
			(fill no)
			(layer "B.CrtYd")
		)
		(fp_rect
			(start 0.381 0.8382)
			(end -0.381 -0.8382)
			(stroke
				(width 0)
				(type default)
			)
			(fill no)
			(layer "B.Fab")
		)
		(pad "1" smd custom
			(at 0 -0.4318 90)
			(size 0.127 0.127)
			(layers "B.Cu" "B.Mask" "B.Paste")
			(net "CLK_100M_PCIE_SAS_DN")
			(options
				(clearance outline)
				(anchor circle)
			)
			(primitives
				(gr_poly
					(pts
						(arc
							(start -0.2032 0.2794)
							(mid -0.239121 0.264521)
							(end -0.254 0.2286)
						)
						(arc
							(start -0.254 -0.2286)
							(mid -0.239121 -0.264521)
							(end -0.2032 -0.2794)
						)
						(arc
							(start 0.2032 -0.2794)
							(mid 0.239121 -0.264521)
							(end 0.254 -0.2286)
						)
						(arc
							(start 0.254 0.2286)
							(mid 0.239121 0.264521)
							(end 0.2032 0.2794)
						)
					)
					(width 0)
					(fill yes)
				)
			)
		)
		(pad "2" smd custom
			(at 0 0.4318 90)
			(size 0.127 0.127)
			(layers "B.Cu" "B.Mask" "B.Paste")
			(net "GND")
			(options
				(clearance outline)
				(anchor circle)
			)
			(primitives
				(gr_poly
					(pts
						(arc
							(start -0.2032 0.2794)
							(mid -0.239121 0.264521)
							(end -0.254 0.2286)
						)
						(arc
							(start -0.254 -0.2286)
							(mid -0.239121 -0.264521)
							(end -0.2032 -0.2794)
						)
						(arc
							(start 0.2032 -0.2794)
							(mid 0.239121 -0.264521)
							(end 0.254 -0.2286)
						)
						(arc
							(start 0.254 0.2286)
							(mid 0.239121 0.264521)
							(end 0.2032 0.2794)
						)
					)
					(width 0)
					(fill yes)
				)
			)
		)
	)
	(footprint ""
		(layer "B.Cu")
		(at 103.124 -52.832 -90)
		(property "Reference" "R285"
			(at 0 0 90)
			(layer "B.SilkS")
			(hide yes)
			(effects
				(font
					(size 1.27 1.27)
				)
				(justify mirror)
			)
		)
		(property "Value" "0R2J-2-GP"
			(at -0.064008 -3.993896 270)
			(unlocked yes)
			(layer "B.Fab")
			(hide yes)
			(effects
				(font
					(size 1.016 1.016)
					(thickness 0.1524)
				)
				(justify mirror)
			)
		)
		(property "Device Type" "R402H16"
			(at -0.064008 -5.517896 270)
			(unlocked yes)
			(layer "B.Fab")
			(hide yes)
			(effects
				(font
					(size 1.016 1.016)
					(thickness 0.1524)
				)
				(justify mirror)
			)
		)
		(duplicate_pad_numbers_are_jumpers no)
		(fp_rect
			(start 0.381 0.8382)
			(end -0.381 -0.8382)
			(stroke
				(width 0)
				(type default)
			)
			(fill no)
			(layer "B.CrtYd")
		)
		(fp_rect
			(start 0.381 0.8382)
			(end -0.381 -0.8382)
			(stroke
				(width 0)
				(type default)
			)
			(fill no)
			(layer "B.Fab")
		)
		(pad "1" smd custom
			(at 0 -0.4318 90)
			(size 0.127 0.127)
			(layers "B.Cu" "B.Mask" "B.Paste")
			(net "M_DRAM_PWROK")
			(options
				(clearance outline)
				(anchor circle)
			)
			(primitives
				(gr_poly
					(pts
						(arc
							(start -0.2032 0.2794)
							(mid -0.239121 0.264521)
							(end -0.254 0.2286)
						)
						(arc
							(start -0.254 -0.2286)
							(mid -0.239121 -0.264521)
							(end -0.2032 -0.2794)
						)
						(arc
							(start 0.2032 -0.2794)
							(mid 0.239121 -0.264521)
							(end 0.254 -0.2286)
						)
						(arc
							(start 0.254 0.2286)
							(mid 0.239121 0.264521)
							(end 0.2032 0.2794)
						)
					)
					(width 0)
					(fill yes)
				)
			)
		)
		(pad "2" smd custom
			(at 0 0.4318 90)
			(size 0.127 0.127)
			(layers "B.Cu" "B.Mask" "B.Paste")
			(net "GND")
			(options
				(clearance outline)
				(anchor circle)
			)
			(primitives
				(gr_poly
					(pts
						(arc
							(start -0.2032 0.2794)
							(mid -0.239121 0.264521)
							(end -0.254 0.2286)
						)
						(arc
							(start -0.254 -0.2286)
							(mid -0.239121 -0.264521)
							(end -0.2032 -0.2794)
						)
						(arc
							(start 0.2032 -0.2794)
							(mid 0.239121 -0.264521)
							(end 0.254 -0.2286)
						)
						(arc
							(start 0.254 0.2286)
							(mid 0.239121 0.264521)
							(end 0.2032 0.2794)
						)
					)
					(width 0)
					(fill yes)
				)
			)
		)
	)
	(footprint ""
		(layer "B.Cu")
		(at 32.258 -53.594 180)
		(property "Reference" "PC125"
			(at 0 0 0)
			(layer "B.SilkS")
			(hide yes)
			(effects
				(font
					(size 1.27 1.27)
				)
				(justify mirror)
			)
		)
		(property "Value" "SCD1U16V2KX-3GP"
			(at -1.8923 -1.2065 180)
			(unlocked yes)
			(layer "B.Fab")
			(hide yes)
			(effects
				(font
					(size 1.016 1.016)
					(thickness 0.1524)
				)
				(justify mirror)
			)
		)
		(property "Device Type" "C402H22"
			(at -1.8923 -2.7305 180)
			(unlocked yes)
			(layer "B.Fab")
			(hide yes)
			(effects
				(font
					(size 1.016 1.016)
					(thickness 0.1524)
				)
				(justify mirror)
			)
		)
		(duplicate_pad_numbers_are_jumpers no)
		(fp_rect
			(start 0.381 0.7366)
			(end -0.381 -0.7366)
			(stroke
				(width 0)
				(type default)
			)
			(fill no)
			(layer "B.CrtYd")
		)
		(fp_rect
			(start 0.381 0.7366)
			(end -0.381 -0.7366)
			(stroke
				(width 0)
				(type default)
			)
			(fill no)
			(layer "B.Fab")
		)
		(pad "1" smd custom
			(at 0 -0.4572)
			(size 0.1143 0.1143)
			(layers "B.Cu" "B.Mask" "B.Paste")
			(net "P1V5_STBY_BIAS")
			(options
				(clearance outline)
				(anchor circle)
			)
			(primitives
				(gr_poly
					(pts
						(arc
							(start -0.254 0.1778)
							(mid -0.239121 0.213721)
							(end -0.2032 0.2286)
						)
						(arc
							(start 0.2032 0.2286)
							(mid 0.239121 0.213721)
							(end 0.254 0.1778)
						)
						(arc
							(start 0.254 -0.1778)
							(mid 0.239121 -0.213721)
							(end 0.2032 -0.2286)
						)
						(arc
							(start -0.2032 -0.2286)
							(mid -0.239121 -0.213721)
							(end -0.254 -0.1778)
						)
					)
					(width 0)
					(fill yes)
				)
			)
		)
		(pad "2" smd custom
			(at 0 0.4572)
			(size 0.1143 0.1143)
			(layers "B.Cu" "B.Mask" "B.Paste")
			(net "GND")
			(options
				(clearance outline)
				(anchor circle)
			)
			(primitives
				(gr_poly
					(pts
						(arc
							(start -0.254 0.1778)
							(mid -0.239121 0.213721)
							(end -0.2032 0.2286)
						)
						(arc
							(start 0.2032 0.2286)
							(mid 0.239121 0.213721)
							(end 0.254 0.1778)
						)
						(arc
							(start 0.254 -0.1778)
							(mid 0.239121 -0.213721)
							(end 0.2032 -0.2286)
						)
						(arc
							(start -0.2032 -0.2286)
							(mid -0.239121 -0.213721)
							(end -0.254 -0.1778)
						)
					)
					(width 0)
					(fill yes)
				)
			)
		)
	)
	(footprint ""
		(layer "B.Cu")
		(at 70.7898 -60.833)
		(property "Reference" "R486"
			(at 0 0 0)
			(layer "B.SilkS")
			(hide yes)
			(effects
				(font
					(size 1.27 1.27)
				)
				(justify mirror)
			)
		)
		(property "Value" "10KR2F-2-GP"
			(at -1.7907 -1.1176 0)
			(unlocked yes)
			(layer "B.Fab")
			(hide yes)
			(effects
				(font
					(size 1.016 1.016)
					(thickness 0.1524)
				)
				(justify mirror)
			)
		)
		(property "Device Type" "R402H16"
			(at -1.7907 -2.6416 0)
			(unlocked yes)
			(layer "B.Fab")
			(hide yes)
			(effects
				(font
					(size 1.016 1.016)
					(thickness 0.1524)
				)
				(justify mirror)
			)
		)
		(duplicate_pad_numbers_are_jumpers no)
		(fp_rect
			(start 0.381 0.8382)
			(end -0.381 -0.8382)
			(stroke
				(width 0)
				(type default)
			)
			(fill no)
			(layer "B.CrtYd")
		)
		(fp_rect
			(start 0.381 0.8382)
			(end -0.381 -0.8382)
			(stroke
				(width 0)
				(type default)
			)
			(fill no)
			(layer "B.Fab")
		)
		(pad "1" smd custom
			(at 0 -0.4318 180)
			(size 0.127 0.127)
			(layers "B.Cu" "B.Mask" "B.Paste")
			(net "P3V3_STBY_SENSE")
			(options
				(clearance outline)
				(anchor circle)
			)
			(primitives
				(gr_poly
					(pts
						(arc
							(start -0.2032 0.2794)
							(mid -0.239121 0.264521)
							(end -0.254 0.2286)
						)
						(arc
							(start -0.254 -0.2286)
							(mid -0.239121 -0.264521)
							(end -0.2032 -0.2794)
						)
						(arc
							(start 0.2032 -0.2794)
							(mid 0.239121 -0.264521)
							(end 0.254 -0.2286)
						)
						(arc
							(start 0.254 0.2286)
							(mid 0.239121 0.264521)
							(end 0.2032 0.2794)
						)
					)
					(width 0)
					(fill yes)
				)
			)
		)
		(pad "2" smd custom
			(at 0 0.4318 180)
			(size 0.127 0.127)
			(layers "B.Cu" "B.Mask" "B.Paste")
			(net "GND")
			(options
				(clearance outline)
				(anchor circle)
			)
			(primitives
				(gr_poly
					(pts
						(arc
							(start -0.2032 0.2794)
							(mid -0.239121 0.264521)
							(end -0.254 0.2286)
						)
						(arc
							(start -0.254 -0.2286)
							(mid -0.239121 -0.264521)
							(end -0.2032 -0.2794)
						)
						(arc
							(start 0.2032 -0.2794)
							(mid 0.239121 -0.264521)
							(end 0.254 -0.2286)
						)
						(arc
							(start 0.254 0.2286)
							(mid 0.239121 0.264521)
							(end 0.2032 0.2794)
						)
					)
					(width 0)
					(fill yes)
				)
			)
		)
	)
	(footprint ""
		(layer "B.Cu")
		(at 17.272 -51.181 180)
		(property "Reference" "R500"
			(at 0 0 0)
			(layer "B.SilkS")
			(hide yes)
			(effects
				(font
					(size 1.27 1.27)
				)
				(justify mirror)
			)
		)
		(property "Value" "150R3F-GP"
			(at 0.0254 -2.0193 180)
			(unlocked yes)
			(layer "B.Fab")
			(hide yes)
			(effects
				(font
					(size 1.016 1.016)
					(thickness 0.1524)
				)
				(justify mirror)
			)
		)
		(property "Device Type" "R603H22"
			(at 0.0254 -3.5433 180)
			(unlocked yes)
			(layer "B.Fab")
			(hide yes)
			(effects
				(font
					(size 1.016 1.016)
					(thickness 0.1524)
				)
				(justify mirror)
			)
		)
		(duplicate_pad_numbers_are_jumpers no)
		(fp_line
			(start 0.2032 0)
			(end 0.4191 0)
			(stroke
				(width 0.2032)
				(type default)
			)
			(layer "B.SilkS")
		)
		(fp_line
			(start -0.4318 0)
			(end -0.2032 0)
			(stroke
				(width 0.2032)
				(type default)
			)
			(layer "B.SilkS")
		)
		(fp_rect
			(start 0.635 1.1811)
			(end -0.635 -1.1811)
			(stroke
				(width 0)
				(type default)
			)
			(fill no)
			(layer "B.CrtYd")
		)
		(fp_rect
			(start 0.635 1.1811)
			(end -0.635 -1.1811)
			(stroke
				(width 0)
				(type default)
			)
			(fill no)
			(layer "B.Fab")
		)
		(pad "1" smd custom
			(at 0 -0.6604)
			(size 0.19685 0.19685)
			(layers "B.Cu" "B.Mask" "B.Paste")
			(net "P3V3")
			(options
				(clearance outline)
				(anchor circle)
			)
			(primitives
				(gr_poly
					(pts
						(arc
							(start 0.508 0.2921)
							(mid 0.478242 0.363942)
							(end 0.4064 0.3937)
						)
						(arc
							(start -0.4064 0.3937)
							(mid -0.478242 0.363942)
							(end -0.508 0.2921)
						)
						(arc
							(start -0.508 -0.2921)
							(mid -0.478242 -0.363942)
							(end -0.4064 -0.3937)
						)
						(arc
							(start 0.4064 -0.3937)
							(mid 0.478242 -0.363942)
							(end 0.508 -0.2921)
						)
					)
					(width 0)
					(fill yes)
				)
			)
		)
		(pad "2" smd custom
			(at 0 0.6604)
			(size 0.19685 0.19685)
			(layers "B.Cu" "B.Mask" "B.Paste")
			(net "P3V3_DISCHARGE_D")
			(options
				(clearance outline)
				(anchor circle)
			)
			(primitives
				(gr_poly
					(pts
						(arc
							(start 0.508 0.2921)
							(mid 0.478242 0.363942)
							(end 0.4064 0.3937)
						)
						(arc
							(start -0.4064 0.3937)
							(mid -0.478242 0.363942)
							(end -0.508 0.2921)
						)
						(arc
							(start -0.508 -0.2921)
							(mid -0.478242 -0.363942)
							(end -0.4064 -0.3937)
						)
						(arc
							(start 0.4064 -0.3937)
							(mid 0.478242 -0.363942)
							(end 0.508 -0.2921)
						)
					)
					(width 0)
					(fill yes)
				)
			)
		)
	)
	(footprint ""
		(layer "B.Cu")
		(at 46.228 -12.7)
		(property "Reference" "C262"
			(at 0 0 0)
			(layer "B.SilkS")
			(hide yes)
			(effects
				(font
					(size 1.27 1.27)
				)
				(justify mirror)
			)
		)
		(property "Value" "SCD1U16V2KX-3GP"
			(at -1.1811 -2.7051 0)
			(unlocked yes)
			(layer "B.Fab")
			(hide yes)
			(effects
				(font
					(size 1.016 1.016)
					(thickness 0.1524)
				)
				(justify mirror)
			)
		)
		(property "Device Type" "C402H22"
			(at -1.1811 -4.2291 0)
			(unlocked yes)
			(layer "B.Fab")
			(hide yes)
			(effects
				(font
					(size 1.016 1.016)
					(thickness 0.1524)
				)
				(justify mirror)
			)
		)
		(duplicate_pad_numbers_are_jumpers no)
		(fp_rect
			(start 0.381 0.7366)
			(end -0.381 -0.7366)
			(stroke
				(width 0)
				(type default)
			)
			(fill no)
			(layer "B.CrtYd")
		)
		(fp_rect
			(start 0.381 0.7366)
			(end -0.381 -0.7366)
			(stroke
				(width 0)
				(type default)
			)
			(fill no)
			(layer "B.Fab")
		)
		(pad "1" smd custom
			(at 0 -0.4572 180)
			(size 0.1143 0.1143)
			(layers "B.Cu" "B.Mask" "B.Paste")
			(net "P2E_CPU_SAS_C_TX_DP4")
			(options
				(clearance outline)
				(anchor circle)
			)
			(primitives
				(gr_poly
					(pts
						(arc
							(start -0.254 0.1778)
							(mid -0.239121 0.213721)
							(end -0.2032 0.2286)
						)
						(arc
							(start 0.2032 0.2286)
							(mid 0.239121 0.213721)
							(end 0.254 0.1778)
						)
						(arc
							(start 0.254 -0.1778)
							(mid 0.239121 -0.213721)
							(end 0.2032 -0.2286)
						)
						(arc
							(start -0.2032 -0.2286)
							(mid -0.239121 -0.213721)
							(end -0.254 -0.1778)
						)
					)
					(width 0)
					(fill yes)
				)
			)
		)
		(pad "2" smd custom
			(at 0 0.4572 180)
			(size 0.1143 0.1143)
			(layers "B.Cu" "B.Mask" "B.Paste")
			(net "P2E_CPU_SAS_TX_DP4")
			(options
				(clearance outline)
				(anchor circle)
			)
			(primitives
				(gr_poly
					(pts
						(arc
							(start -0.254 0.1778)
							(mid -0.239121 0.213721)
							(end -0.2032 0.2286)
						)
						(arc
							(start 0.2032 0.2286)
							(mid 0.239121 0.213721)
							(end 0.254 0.1778)
						)
						(arc
							(start 0.254 -0.1778)
							(mid 0.239121 -0.213721)
							(end 0.2032 -0.2286)
						)
						(arc
							(start -0.2032 -0.2286)
							(mid -0.239121 -0.213721)
							(end -0.254 -0.1778)
						)
					)
					(width 0)
					(fill yes)
				)
			)
		)
	)
)
